(kicad_pcb
	(version 20260206)
	(generator "pcbnew")
	(generator_version "10.0")
	(general
		(thickness 1.6)
		(legacy_teardrops no)
	)
	(paper "A4")
	(title_block
		(title "v2-pdb — ms_pdb_v2.brd")
		(comment 1 "Open CloudServer (Microsoft) / footprints 335-335 of 348")
	)
	(layers
		(0 "F.Cu" signal "TOP")
		(4 "In1.Cu" signal "GND")
		(6 "In2.Cu" signal "IN1")
		(8 "In3.Cu" signal "VCC")
		(10 "In4.Cu" signal "VCC1")
		(12 "In5.Cu" signal "IN2")
		(14 "In6.Cu" signal "GND1")
		(2 "B.Cu" signal "BOTTOM")
		(9 "F.Adhes" user "F.Adhesive")
		(11 "B.Adhes" user "B.Adhesive")
		(13 "F.Paste" user "Package Geometry/Pastemask Top")
		(15 "B.Paste" user "Package Geometry/Pastemask Bottom")
		(5 "F.SilkS" user "Ref Des/Silkscreen Top")
		(7 "B.SilkS" user "Ref Des/Silkscreen Bottom")
		(1 "F.Mask" user "Board Geometry/Soldermask Top")
		(3 "B.Mask" user "Board Geometry/Soldermask Bottom")
		(17 "Dwgs.User" user "User.Drawings")
		(19 "Cmts.User" user "User.Comments")
		(21 "Eco1.User" user "User.Eco1")
		(23 "Eco2.User" user "User.Eco2")
		(25 "Edge.Cuts" user "Board Geometry/Outline")
		(27 "Margin" user)
		(31 "F.CrtYd" user "Package Geometry/Place Bound Top")
		(29 "B.CrtYd" user "Package Geometry/Place Bound Bottom")
		(35 "F.Fab" user "Ref Des/Assembly Top")
		(33 "B.Fab" user "Ref Des/Assembly Bottom")
	)
	(footprint ""
		(layer "B.Cu")
		(at 87.585804 -516.95858)
		(property "Reference" ""
			(at 0 0 0)
			(layer "B.SilkS")
			(hide yes)
			(effects
				(font
					(size 1.27 1.27)
				)
				(justify mirror)
			)
		)
		(property "Value" ""
			(at 0 0 0)
			(layer "B.Fab")
			(effects
				(font
					(size 1.27 1.27)
				)
				(justify mirror)
			)
		)
		(duplicate_pad_numbers_are_jumpers no)
		(fp_poly
			(pts
				(arc
					(start 1.4986 0)
					(mid -1.4986 0)
					(end 1.4986 0)
				)
			)
			(stroke
				(width 0)
				(type default)
			)
			(fill no)
			(layer "B.CrtYd")
		)
		(pad "1" smd circle
			(at 0 0 180)
			(size 0.9906 0.9906)
			(layers "B.Cu" "B.Mask" "B.Paste")
			(net "Net_71")
		)
		(zone
			(layer "B.Cu")
			(hatch none 0.5)
			(connect_pads
				(clearance 0)
			)
			(min_thickness 0.25)
			(keepout
				(tracks not_allowed)
				(vias allowed)
				(pads allowed)
				(copperpour not_allowed)
				(footprints allowed)
			)
			(placement
				(enabled no)
				(sheetname "")
			)
			(fill
				(thermal_gap 0.5)
				(thermal_bridge_width 0.5)
				(island_removal_mode 0)
			)
			(polygon
				(pts
					(arc
						(start 89.211404 -516.95858)
						(mid 85.960204 -516.95858)
						(end 89.211404 -516.95858)
					)
				)
			)
		)
	)
)
